(kicad_pcb
	(version 20260206)
	(generator "pcbnew")
	(generator_version "10.0")
	(general
		(thickness 1.6)
		(legacy_teardrops no)
	)
	(paper "A4")
	(title_block
		(title "dpb — 14545-sa.0730WZS0815.brd")
		(comment 1 "Honey Badger (Wiwynn) / footprints 1022-1026 of 1066")
	)
	(layers
		(0 "F.Cu" signal "TOP")
		(4 "In1.Cu" signal "L2GND")
		(6 "In2.Cu" signal "L3")
		(8 "In3.Cu" signal "L4VCC")
		(10 "In4.Cu" signal "L5VCC")
		(12 "In5.Cu" signal "L6")
		(14 "In6.Cu" signal "L7GND")
		(2 "B.Cu" signal "BOTTOM")
		(9 "F.Adhes" user "F.Adhesive")
		(11 "B.Adhes" user "B.Adhesive")
		(13 "F.Paste" user "Package Geometry/Pastemask Top")
		(15 "B.Paste" user "Package Geometry/Pastemask Bottom")
		(5 "F.SilkS" user "Ref Des/Silkscreen Top")
		(7 "B.SilkS" user "Ref Des/Silkscreen Bottom")
		(1 "F.Mask" user "Board Geometry/Soldermask Top")
		(3 "B.Mask" user "Board Geometry/Soldermask Bottom")
		(17 "Dwgs.User" user "User.Drawings")
		(19 "Cmts.User" user "User.Comments")
		(21 "Eco1.User" user "User.Eco1")
		(23 "Eco2.User" user "User.Eco2")
		(25 "Edge.Cuts" user "Board Geometry/Outline")
		(27 "Margin" user)
		(31 "F.CrtYd" user "Package Geometry/Place Bound Top")
		(29 "B.CrtYd" user "Package Geometry/Place Bound Bottom")
		(35 "F.Fab" user "Ref Des/Assembly Top")
		(33 "B.Fab" user "Ref Des/Assembly Bottom")
	)
	(footprint ""
		(layer "F.Cu")
		(at 58.7756 -380.8222 90)
		(property "Reference" "R378"
			(at 0 0 90)
			(layer "F.SilkS")
			(hide yes)
			(effects
				(font
					(size 1.27 1.27)
				)
			)
		)
		(property "Value" "0R2J-2-GP"
			(at 0.064008 -3.993896 90)
			(unlocked yes)
			(layer "F.Fab")
			(hide yes)
			(effects
				(font
					(size 1.016 1.016)
					(thickness 0.1524)
				)
			)
		)
		(property "Device Type" "R402H16"
			(at 0.064008 -5.517896 90)
			(unlocked yes)
			(layer "F.Fab")
			(hide yes)
			(effects
				(font
					(size 1.016 1.016)
					(thickness 0.1524)
				)
			)
		)
		(duplicate_pad_numbers_are_jumpers no)
		(fp_line
			(start 0.508 -0.9398)
			(end -0.508 -0.9398)
			(stroke
				(width 0.1524)
				(type default)
			)
			(layer "F.SilkS")
		)
		(fp_line
			(start -0.508 -0.9398)
			(end -0.508 0.9398)
			(stroke
				(width 0.1524)
				(type default)
			)
			(layer "F.SilkS")
		)
		(fp_rect
			(start -0.508 0.9398)
			(end 0.508 -0.9398)
			(stroke
				(width 0)
				(type default)
			)
			(fill no)
			(layer "F.CrtYd")
		)
		(fp_rect
			(start -0.508 0.9398)
			(end 0.508 -0.9398)
			(stroke
				(width 0)
				(type default)
			)
			(fill no)
			(layer "F.Fab")
		)
		(pad "1" smd custom
			(at 0 -0.4445 90)
			(size 0.1397 0.1397)
			(layers "F.Cu" "F.Mask" "F.Paste")
			(net "HDD_PRSNT_NET6")
			(options
				(clearance outline)
				(anchor circle)
			)
			(primitives
				(gr_poly
					(pts
						(arc
							(start -0.1778 -0.2794)
							(mid -0.249642 -0.249642)
							(end -0.2794 -0.1778)
						)
						(arc
							(start -0.2794 0.1778)
							(mid -0.249642 0.249642)
							(end -0.1778 0.2794)
						)
						(arc
							(start 0.1778 0.2794)
							(mid 0.249642 0.249642)
							(end 0.2794 0.1778)
						)
						(arc
							(start 0.2794 -0.1778)
							(mid 0.249642 -0.249642)
							(end 0.1778 -0.2794)
						)
					)
					(width 0)
					(fill yes)
				)
			)
		)
		(pad "2" smd custom
			(at 0 0.4445 90)
			(size 0.1397 0.1397)
			(layers "F.Cu" "F.Mask" "F.Paste")
			(net "HDD6_LED_B")
			(options
				(clearance outline)
				(anchor circle)
			)
			(primitives
				(gr_poly
					(pts
						(arc
							(start -0.1778 -0.2794)
							(mid -0.249642 -0.249642)
							(end -0.2794 -0.1778)
						)
						(arc
							(start -0.2794 0.1778)
							(mid -0.249642 0.249642)
							(end -0.1778 0.2794)
						)
						(arc
							(start 0.1778 0.2794)
							(mid 0.249642 0.249642)
							(end 0.2794 0.1778)
						)
						(arc
							(start 0.2794 -0.1778)
							(mid 0.249642 -0.249642)
							(end 0.1778 -0.2794)
						)
					)
					(width 0)
					(fill yes)
				)
			)
		)
	)
	(footprint ""
		(layer "F.Cu")
		(at 26.288746 -474.9927 90)
		(property "Reference" "PTC6"
			(at 0 0 90)
			(layer "F.SilkS")
			(hide yes)
			(effects
				(font
					(size 1.27 1.27)
				)
			)
		)
		(property "Value" "ST330U10VDM-2GP"
			(at 0 -9.6012 90)
			(unlocked yes)
			(layer "F.Fab")
			(hide yes)
			(effects
				(font
					(size 1.016 1.016)
					(thickness 0.1524)
				)
			)
		)
		(property "Device Type" "CT7343H150"
			(at 0 -11.1252 90)
			(unlocked yes)
			(layer "F.Fab")
			(hide yes)
			(effects
				(font
					(size 1.016 1.016)
					(thickness 0.1524)
				)
			)
		)
		(duplicate_pad_numbers_are_jumpers no)
		(fp_line
			(start 2.286 -4.8768)
			(end -2.286 -4.8768)
			(stroke
				(width 0.1524)
				(type default)
			)
			(layer "F.SilkS")
		)
		(fp_line
			(start -2.286 -4.8768)
			(end -2.286 -2.032)
			(stroke
				(width 0.1524)
				(type default)
			)
			(layer "F.SilkS")
		)
		(fp_line
			(start 2.1082 -4.699)
			(end -2.1082 -4.699)
			(stroke
				(width 0.508)
				(type default)
			)
			(layer "F.SilkS")
		)
		(fp_line
			(start 2.286 -2.032)
			(end 2.286 -4.8768)
			(stroke
				(width 0.1524)
				(type default)
			)
			(layer "F.SilkS")
		)
		(fp_line
			(start 2.286 2.032)
			(end 2.286 4.8768)
			(stroke
				(width 0.1524)
				(type default)
			)
			(layer "F.SilkS")
		)
		(fp_line
			(start 2.286 4.8768)
			(end -2.286 4.8768)
			(stroke
				(width 0.1524)
				(type default)
			)
			(layer "F.SilkS")
		)
		(fp_line
			(start -2.286 4.8768)
			(end -2.286 2.032)
			(stroke
				(width 0.1524)
				(type default)
			)
			(layer "F.SilkS")
		)
		(fp_rect
			(start -2.1463 3.6449)
			(end 2.1463 -3.6449)
			(stroke
				(width 0)
				(type default)
			)
			(fill no)
			(layer "F.CrtYd")
		)
		(fp_poly
			(pts
				(xy -2.54 4.953) (xy -2.54 4.2926) (xy -3.81 4.2926) (xy -3.81 -4.2926) (xy -2.54 -4.2926) (xy -2.54 -4.953)
				(xy 2.54 -4.953) (xy 2.54 -4.2926) (xy 3.81 -4.2926) (xy 3.81 -1.6256) (xy 2.1463 -1.6256) (xy 2.1463 -3.6449)
				(xy -2.1463 -3.6449) (xy -2.1463 3.6449) (xy 2.1463 3.6449) (xy 2.1463 -1.6129) (xy 3.81 -1.6129)
				(xy 3.81 4.2926) (xy 2.54 4.2926) (xy 2.54 4.953)
			)
			(stroke
				(width 0)
				(type default)
			)
			(fill no)
			(layer "F.CrtYd")
		)
		(fp_rect
			(start 2.54 4.2926)
			(end 3.81 -4.2926)
			(stroke
				(width 0)
				(type default)
			)
			(fill no)
			(layer "F.Fab")
		)
		(fp_rect
			(start -3.81 4.2926)
			(end -2.54 -4.2926)
			(stroke
				(width 0)
				(type default)
			)
			(fill no)
			(layer "F.Fab")
		)
		(fp_rect
			(start -2.54 4.953)
			(end 2.54 -4.953)
			(stroke
				(width 0)
				(type default)
			)
			(fill no)
			(layer "F.Fab")
		)
		(pad "1" smd rect
			(at 0 -3.1496 90)
			(size 2.413 2.286)
			(layers "F.Cu" "F.Mask" "F.Paste")
			(net "P5VC")
		)
		(pad "2" smd rect
			(at 0 3.1496 90)
			(size 2.413 2.286)
			(layers "F.Cu" "F.Mask" "F.Paste")
			(net "GND")
		)
		(zone
			(layer "F.Cu")
			(hatch none 0.5)
			(connect_pads
				(clearance 0)
			)
			(min_thickness 0.25)
			(keepout
				(tracks allowed)
				(vias not_allowed)
				(pads allowed)
				(copperpour not_allowed)
				(footprints allowed)
			)
			(placement
				(enabled no)
				(sheetname "")
			)
			(fill
				(thermal_gap 0.5)
				(thermal_bridge_width 0.5)
				(island_removal_mode 0)
			)
			(polygon
				(pts
					(xy 24.599646 -476.504) (xy 21.691346 -476.504) (xy 21.691346 -473.4814) (xy 24.586946 -473.4814)
					(xy 24.917146 -473.4814) (xy 24.917146 -476.504)
				)
			)
		)
		(zone
			(layer "F.Cu")
			(hatch none 0.5)
			(connect_pads
				(clearance 0)
			)
			(min_thickness 0.25)
			(keepout
				(tracks allowed)
				(vias not_allowed)
				(pads allowed)
				(copperpour not_allowed)
				(footprints allowed)
			)
			(placement
				(enabled no)
				(sheetname "")
			)
			(fill
				(thermal_gap 0.5)
				(thermal_bridge_width 0.5)
				(island_removal_mode 0)
			)
			(polygon
				(pts
					(xy 30.886146 -473.4814) (xy 30.886146 -476.504) (xy 27.990546 -476.504) (xy 27.660346 -476.504)
					(xy 27.660346 -473.4814) (xy 27.990546 -473.4814)
				)
			)
		)
	)
	(footprint ""
		(layer "F.Cu")
		(at 21.399246 -464.467702 -90)
		(property "Reference" "R241"
			(at 0 0 270)
			(layer "F.SilkS")
			(hide yes)
			(effects
				(font
					(size 1.27 1.27)
				)
			)
		)
		(property "Value" "402R2F-GP"
			(at 0.064008 -3.993896 270)
			(unlocked yes)
			(layer "F.Fab")
			(hide yes)
			(effects
				(font
					(size 1.016 1.016)
					(thickness 0.1524)
				)
			)
		)
		(property "Device Type" "R402H16"
			(at 0.064008 -5.517896 270)
			(unlocked yes)
			(layer "F.Fab")
			(hide yes)
			(effects
				(font
					(size 1.016 1.016)
					(thickness 0.1524)
				)
			)
		)
		(duplicate_pad_numbers_are_jumpers no)
		(fp_line
			(start -0.508 -0.9398)
			(end -0.508 0.9398)
			(stroke
				(width 0.1524)
				(type default)
			)
			(layer "F.SilkS")
		)
		(fp_line
			(start 0.508 -0.9398)
			(end -0.508 -0.9398)
			(stroke
				(width 0.1524)
				(type default)
			)
			(layer "F.SilkS")
		)
		(fp_rect
			(start -0.508 0.9398)
			(end 0.508 -0.9398)
			(stroke
				(width 0)
				(type default)
			)
			(fill no)
			(layer "F.CrtYd")
		)
		(fp_rect
			(start -0.508 0.9398)
			(end 0.508 -0.9398)
			(stroke
				(width 0)
				(type default)
			)
			(fill no)
			(layer "F.Fab")
		)
		(pad "1" smd custom
			(at 0 -0.4445 270)
			(size 0.1397 0.1397)
			(layers "F.Cu" "F.Mask" "F.Paste")
			(net "P5VC_HDD10_LED")
			(options
				(clearance outline)
				(anchor circle)
			)
			(primitives
				(gr_poly
					(pts
						(arc
							(start -0.1778 -0.2794)
							(mid -0.249642 -0.249642)
							(end -0.2794 -0.1778)
						)
						(arc
							(start -0.2794 0.1778)
							(mid -0.249642 0.249642)
							(end -0.1778 0.2794)
						)
						(arc
							(start 0.1778 0.2794)
							(mid 0.249642 0.249642)
							(end 0.2794 0.1778)
						)
						(arc
							(start 0.2794 -0.1778)
							(mid 0.249642 -0.249642)
							(end 0.1778 -0.2794)
						)
					)
					(width 0)
					(fill yes)
				)
			)
		)
		(pad "2" smd custom
			(at 0 0.4445 270)
			(size 0.1397 0.1397)
			(layers "F.Cu" "F.Mask" "F.Paste")
			(net "DRV_ACT_10")
			(options
				(clearance outline)
				(anchor circle)
			)
			(primitives
				(gr_poly
					(pts
						(arc
							(start -0.1778 -0.2794)
							(mid -0.249642 -0.249642)
							(end -0.2794 -0.1778)
						)
						(arc
							(start -0.2794 0.1778)
							(mid -0.249642 0.249642)
							(end -0.1778 0.2794)
						)
						(arc
							(start 0.1778 0.2794)
							(mid 0.249642 0.249642)
							(end 0.2794 0.1778)
						)
						(arc
							(start 0.2794 -0.1778)
							(mid 0.249642 -0.249642)
							(end 0.1778 -0.2794)
						)
					)
					(width 0)
					(fill yes)
				)
			)
		)
	)
	(footprint ""
		(layer "F.Cu")
		(at 218.490546 -346.1512 -90)
		(property "Reference" "Q35"
			(at 0 0 270)
			(layer "F.SilkS")
			(hide yes)
			(effects
				(font
					(size 1.27 1.27)
				)
			)
		)
		(property "Value" "PMBS3904-1-GP"
			(at 0 -9.0932 270)
			(unlocked yes)
			(layer "F.Fab")
			(hide yes)
			(effects
				(font
					(size 1.016 1.016)
					(thickness 0.1524)
				)
			)
		)
		(property "Device Type" "SOT-23-10H44"
			(at 0 -10.6172 270)
			(unlocked yes)
			(layer "F.Fab")
			(hide yes)
			(effects
				(font
					(size 1.016 1.016)
					(thickness 0.1524)
				)
			)
		)
		(duplicate_pad_numbers_are_jumpers no)
		(fp_line
			(start -1.279144 2.15265)
			(end -0.701294 2.15265)
			(stroke
				(width 0.0127)
				(type default)
			)
			(layer "F.SilkS")
		)
		(fp_line
			(start -0.71628 2.15265)
			(end -1.26492 2.15265)
			(stroke
				(width 0.0127)
				(type default)
			)
			(layer "F.SilkS")
		)
		(fp_line
			(start -1.279398 2.152142)
			(end -0.9906 1.86309)
			(stroke
				(width 0.0127)
				(type default)
			)
			(layer "F.SilkS")
		)
		(fp_line
			(start -0.719074 2.145538)
			(end -1.265936 2.14122)
			(stroke
				(width 0.0127)
				(type default)
			)
			(layer "F.SilkS")
		)
		(fp_line
			(start -1.260856 2.1336)
			(end -0.720344 2.1336)
			(stroke
				(width 0.0127)
				(type default)
			)
			(layer "F.SilkS")
		)
		(fp_line
			(start -1.251458 2.124202)
			(end -0.729996 2.124202)
			(stroke
				(width 0.0127)
				(type default)
			)
			(layer "F.SilkS")
		)
		(fp_line
			(start -1.241806 2.11455)
			(end -0.739394 2.11455)
			(stroke
				(width 0.0127)
				(type default)
			)
			(layer "F.SilkS")
		)
		(fp_line
			(start -1.232408 2.105152)
			(end -0.749046 2.105152)
			(stroke
				(width 0.0127)
				(type default)
			)
			(layer "F.SilkS")
		)
		(fp_line
			(start -1.222756 2.0955)
			(end -0.758444 2.0955)
			(stroke
				(width 0.0127)
				(type default)
			)
			(layer "F.SilkS")
		)
		(fp_line
			(start -1.213358 2.086102)
			(end -0.768096 2.086102)
			(stroke
				(width 0.0127)
				(type default)
			)
			(layer "F.SilkS")
		)
		(fp_line
			(start -1.203706 2.07645)
			(end -0.777494 2.07645)
			(stroke
				(width 0.0127)
				(type default)
			)
			(layer "F.SilkS")
		)
		(fp_line
			(start -1.194308 2.067052)
			(end -0.787146 2.067052)
			(stroke
				(width 0.0127)
				(type default)
			)
			(layer "F.SilkS")
		)
		(fp_line
			(start -1.184656 2.0574)
			(end -0.796544 2.0574)
			(stroke
				(width 0.0127)
				(type default)
			)
			(layer "F.SilkS")
		)
		(fp_line
			(start -1.175258 2.048002)
			(end -0.806196 2.048002)
			(stroke
				(width 0.0127)
				(type default)
			)
			(layer "F.SilkS")
		)
		(fp_line
			(start -1.165606 2.03835)
			(end -0.815594 2.03835)
			(stroke
				(width 0.0127)
				(type default)
			)
			(layer "F.SilkS")
		)
		(fp_line
			(start -1.156208 2.028952)
			(end -0.825246 2.028952)
			(stroke
				(width 0.0127)
				(type default)
			)
			(layer "F.SilkS")
		)
		(fp_line
			(start -1.146556 2.0193)
			(end -0.834644 2.0193)
			(stroke
				(width 0.0127)
				(type default)
			)
			(layer "F.SilkS")
		)
		(fp_line
			(start -1.137158 2.009902)
			(end -0.844296 2.009902)
			(stroke
				(width 0.0127)
				(type default)
			)
			(layer "F.SilkS")
		)
		(fp_line
			(start -1.127506 2.00025)
			(end -0.853694 2.00025)
			(stroke
				(width 0.0127)
				(type default)
			)
			(layer "F.SilkS")
		)
		(fp_line
			(start -1.118108 1.990852)
			(end -0.863346 1.990852)
			(stroke
				(width 0.0127)
				(type default)
			)
			(layer "F.SilkS")
		)
		(fp_line
			(start -1.108456 1.9812)
			(end -0.872744 1.9812)
			(stroke
				(width 0.0127)
				(type default)
			)
			(layer "F.SilkS")
		)
		(fp_line
			(start -1.099058 1.971802)
			(end -0.882396 1.971802)
			(stroke
				(width 0.0127)
				(type default)
			)
			(layer "F.SilkS")
		)
		(fp_line
			(start -1.089406 1.96215)
			(end -0.891794 1.96215)
			(stroke
				(width 0.0127)
				(type default)
			)
			(layer "F.SilkS")
		)
		(fp_line
			(start -1.080008 1.952752)
			(end -0.901446 1.952752)
			(stroke
				(width 0.0127)
				(type default)
			)
			(layer "F.SilkS")
		)
		(fp_line
			(start -1.070356 1.9431)
			(end -0.910844 1.9431)
			(stroke
				(width 0.0127)
				(type default)
			)
			(layer "F.SilkS")
		)
		(fp_line
			(start -1.060958 1.933702)
			(end -0.920496 1.933702)
			(stroke
				(width 0.0127)
				(type default)
			)
			(layer "F.SilkS")
		)
		(fp_line
			(start -1.051306 1.92405)
			(end -0.929894 1.92405)
			(stroke
				(width 0.0127)
				(type default)
			)
			(layer "F.SilkS")
		)
		(fp_line
			(start -1.041908 1.914652)
			(end -0.939546 1.914652)
			(stroke
				(width 0.0127)
				(type default)
			)
			(layer "F.SilkS")
		)
		(fp_line
			(start -1.032256 1.905)
			(end -0.948944 1.905)
			(stroke
				(width 0.0127)
				(type default)
			)
			(layer "F.SilkS")
		)
		(fp_line
			(start -1.022858 1.895602)
			(end -0.958596 1.895602)
			(stroke
				(width 0.0127)
				(type default)
			)
			(layer "F.SilkS")
		)
		(fp_line
			(start -1.013206 1.88595)
			(end -0.967994 1.88595)
			(stroke
				(width 0.0127)
				(type default)
			)
			(layer "F.SilkS")
		)
		(fp_line
			(start -1.7526 1.8796)
			(end -1.7526 0.9906)
			(stroke
				(width 0.3302)
				(type default)
			)
			(layer "F.SilkS")
		)
		(fp_line
			(start -0.635 1.8796)
			(end -1.7526 1.8796)
			(stroke
				(width 0.3302)
				(type default)
			)
			(layer "F.SilkS")
		)
		(fp_line
			(start -1.003808 1.876552)
			(end -0.977646 1.876552)
			(stroke
				(width 0.0127)
				(type default)
			)
			(layer "F.SilkS")
		)
		(fp_line
			(start -0.994156 1.8669)
			(end -0.987044 1.8669)
			(stroke
				(width 0.0127)
				(type default)
			)
			(layer "F.SilkS")
		)
		(fp_line
			(start -0.9906 1.86309)
			(end -0.701294 2.15265)
			(stroke
				(width 0.0127)
				(type default)
			)
			(layer "F.SilkS")
		)
		(fp_line
			(start -1.651 1.778)
			(end 1.651 1.778)
			(stroke
				(width 0.1524)
				(type default)
			)
			(layer "F.SilkS")
		)
		(fp_line
			(start 1.651 1.778)
			(end 1.651 -1.778)
			(stroke
				(width 0.1524)
				(type default)
			)
			(layer "F.SilkS")
		)
		(fp_line
			(start -1.651 -1.778)
			(end -1.651 1.778)
			(stroke
				(width 0.1524)
				(type default)
			)
			(layer "F.SilkS")
		)
		(fp_line
			(start 1.651 -1.778)
			(end -1.651 -1.778)
			(stroke
				(width 0.1524)
				(type default)
			)
			(layer "F.SilkS")
		)
		(fp_poly
			(pts
				(xy -1.285748 2.159) (xy -1.285748 1.8796) (xy -1.778 1.8796) (xy -1.778 -1.8796) (xy 1.778 -1.8796)
				(xy 1.778 1.8796) (xy -0.694944 1.8796) (xy -0.694944 2.159)
			)
			(stroke
				(width 0)
				(type default)
			)
			(fill no)
			(layer "F.CrtYd")
		)
		(fp_poly
			(pts
				(xy -1.285748 2.159) (xy -1.285748 1.8796) (xy -1.778 1.8796) (xy -1.778 -1.8796) (xy 1.778 -1.8796)
				(xy 1.778 1.8796) (xy -0.694944 1.8796) (xy -0.694944 2.159)
			)
			(stroke
				(width 0)
				(type default)
			)
			(fill no)
			(layer "F.Fab")
		)
		(pad "1" smd rect
			(at -0.98425 0.9525 270)
			(size 0.762 1.143)
			(layers "F.Cu" "F.Mask" "F.Paste")
			(net "FLT_HDD1_B")
		)
		(pad "2" smd rect
			(at 0.98425 0.9525 270)
			(size 0.762 1.143)
			(layers "F.Cu" "F.Mask" "F.Paste")
			(net "GND")
		)
		(pad "3" smd rect
			(at 0 -0.9525 270)
			(size 0.762 1.143)
			(layers "F.Cu" "F.Mask" "F.Paste")
			(net "DRIVE_ACT_1")
		)
	)
	(footprint ""
		(layer "F.Cu")
		(at 221.031054 -434.7591 180)
		(property "Reference" "PC41"
			(at 0 0 180)
			(layer "F.SilkS")
			(hide yes)
			(effects
				(font
					(size 1.27 1.27)
				)
			)
		)
		(property "Value" "SCD1U16V2KX-3GP"
			(at 1.1811 -2.7051 180)
			(unlocked yes)
			(layer "F.Fab")
			(hide yes)
			(effects
				(font
					(size 1.016 1.016)
					(thickness 0.1524)
				)
			)
		)
		(property "Device Type" "C402H22"
			(at 1.1811 -4.2291 180)
			(unlocked yes)
			(layer "F.Fab")
			(hide yes)
			(effects
				(font
					(size 1.016 1.016)
					(thickness 0.1524)
				)
			)
		)
		(duplicate_pad_numbers_are_jumpers no)
		(fp_rect
			(start -0.4318 0.9525)
			(end 0.4318 -0.9525)
			(stroke
				(width 0)
				(type default)
			)
			(fill no)
			(layer "F.CrtYd")
		)
		(fp_rect
			(start -0.4318 0.9525)
			(end 0.4318 -0.9525)
			(stroke
				(width 0)
				(type default)
			)
			(fill no)
			(layer "F.Fab")
		)
		(pad "1" smd custom
			(at 0 -0.4445 180)
			(size 0.1524 0.1524)
			(layers "F.Cu" "F.Mask" "F.Paste")
			(net "P3V3_BS_NET")
			(options
				(clearance outline)
				(anchor circle)
			)
			(primitives
				(gr_poly
					(pts
						(arc
							(start 0.3048 -0.2032)
							(mid 0.275042 -0.275042)
							(end 0.2032 -0.3048)
						)
						(arc
							(start -0.2032 -0.3048)
							(mid -0.275042 -0.275042)
							(end -0.3048 -0.2032)
						)
						(arc
							(start -0.3048 0.2032)
							(mid -0.275042 0.275042)
							(end -0.2032 0.3048)
						)
						(arc
							(start 0.2032 0.3048)
							(mid 0.275042 0.275042)
							(end 0.3048 0.2032)
						)
					)
					(width 0)
					(fill yes)
				)
			)
		)
		(pad "2" smd custom
			(at 0 0.4445 180)
			(size 0.1524 0.1524)
			(layers "F.Cu" "F.Mask" "F.Paste")
			(net "P3V3_LX")
			(options
				(clearance outline)
				(anchor circle)
			)
			(primitives
				(gr_poly
					(pts
						(arc
							(start 0.3048 -0.2032)
							(mid 0.275042 -0.275042)
							(end 0.2032 -0.3048)
						)
						(arc
							(start -0.2032 -0.3048)
							(mid -0.275042 -0.275042)
							(end -0.3048 -0.2032)
						)
						(arc
							(start -0.3048 0.2032)
							(mid -0.275042 0.275042)
							(end -0.2032 0.3048)
						)
						(arc
							(start 0.2032 0.3048)
							(mid 0.275042 0.275042)
							(end 0.3048 0.2032)
						)
					)
					(width 0)
					(fill yes)
				)
			)
		)
	)
)
